(kicad_pcb
	(version 20260206)
	(generator "pcbnew")
	(generator_version "10.0")
	(general
		(thickness 1.6)
		(legacy_teardrops no)
	)
	(paper "A4")
	(title_block
		(title "dpb — 14545-sa.0730WZS0815.brd")
		(comment 1 "Honey Badger (Wiwynn) / footprints 734-740 of 1066")
	)
	(layers
		(0 "F.Cu" signal "TOP")
		(4 "In1.Cu" signal "L2GND")
		(6 "In2.Cu" signal "L3")
		(8 "In3.Cu" signal "L4VCC")
		(10 "In4.Cu" signal "L5VCC")
		(12 "In5.Cu" signal "L6")
		(14 "In6.Cu" signal "L7GND")
		(2 "B.Cu" signal "BOTTOM")
		(9 "F.Adhes" user "F.Adhesive")
		(11 "B.Adhes" user "B.Adhesive")
		(13 "F.Paste" user "Package Geometry/Pastemask Top")
		(15 "B.Paste" user "Package Geometry/Pastemask Bottom")
		(5 "F.SilkS" user "Ref Des/Silkscreen Top")
		(7 "B.SilkS" user "Ref Des/Silkscreen Bottom")
		(1 "F.Mask" user "Board Geometry/Soldermask Top")
		(3 "B.Mask" user "Board Geometry/Soldermask Bottom")
		(17 "Dwgs.User" user "User.Drawings")
		(19 "Cmts.User" user "User.Comments")
		(21 "Eco1.User" user "User.Eco1")
		(23 "Eco2.User" user "User.Eco2")
		(25 "Edge.Cuts" user "Board Geometry/Outline")
		(27 "Margin" user)
		(31 "F.CrtYd" user "Package Geometry/Place Bound Top")
		(29 "B.CrtYd" user "Package Geometry/Place Bound Bottom")
		(35 "F.Fab" user "Ref Des/Assembly Top")
		(33 "B.Fab" user "Ref Des/Assembly Bottom")
	)
	(footprint ""
		(layer "F.Cu")
		(at 25.527 -280.797 180)
		(property "Reference" "R415"
			(at 0 0 180)
			(layer "F.SilkS")
			(hide yes)
			(effects
				(font
					(size 1.27 1.27)
				)
			)
		)
		(property "Value" "0R2J-2-GP"
			(at 0.064008 -3.993896 180)
			(unlocked yes)
			(layer "F.Fab")
			(hide yes)
			(effects
				(font
					(size 1.016 1.016)
					(thickness 0.1524)
				)
			)
		)
		(property "Device Type" "R402H16"
			(at 0.064008 -5.517896 180)
			(unlocked yes)
			(layer "F.Fab")
			(hide yes)
			(effects
				(font
					(size 1.016 1.016)
					(thickness 0.1524)
				)
			)
		)
		(duplicate_pad_numbers_are_jumpers no)
		(fp_line
			(start 0.508 -0.9398)
			(end -0.508 -0.9398)
			(stroke
				(width 0.1524)
				(type default)
			)
			(layer "F.SilkS")
		)
		(fp_line
			(start -0.508 -0.9398)
			(end -0.508 0.9398)
			(stroke
				(width 0.1524)
				(type default)
			)
			(layer "F.SilkS")
		)
		(fp_rect
			(start -0.508 0.9398)
			(end 0.508 -0.9398)
			(stroke
				(width 0)
				(type default)
			)
			(fill no)
			(layer "F.CrtYd")
		)
		(fp_rect
			(start -0.508 0.9398)
			(end 0.508 -0.9398)
			(stroke
				(width 0)
				(type default)
			)
			(fill no)
			(layer "F.Fab")
		)
		(pad "1" smd custom
			(at 0 -0.4445 180)
			(size 0.1397 0.1397)
			(layers "F.Cu" "F.Mask" "F.Paste")
			(net "SW_HDD7_G")
			(options
				(clearance outline)
				(anchor circle)
			)
			(primitives
				(gr_poly
					(pts
						(arc
							(start -0.1778 -0.2794)
							(mid -0.249642 -0.249642)
							(end -0.2794 -0.1778)
						)
						(arc
							(start -0.2794 0.1778)
							(mid -0.249642 0.249642)
							(end -0.1778 0.2794)
						)
						(arc
							(start 0.1778 0.2794)
							(mid 0.249642 0.249642)
							(end 0.2794 0.1778)
						)
						(arc
							(start 0.2794 -0.1778)
							(mid 0.249642 -0.249642)
							(end 0.1778 -0.2794)
						)
					)
					(width 0)
					(fill yes)
				)
			)
		)
		(pad "2" smd custom
			(at 0 0.4445 180)
			(size 0.1397 0.1397)
			(layers "F.Cu" "F.Mask" "F.Paste")
			(net "SW_HDD7_R")
			(options
				(clearance outline)
				(anchor circle)
			)
			(primitives
				(gr_poly
					(pts
						(arc
							(start -0.1778 -0.2794)
							(mid -0.249642 -0.249642)
							(end -0.2794 -0.1778)
						)
						(arc
							(start -0.2794 0.1778)
							(mid -0.249642 0.249642)
							(end -0.1778 0.2794)
						)
						(arc
							(start 0.1778 0.2794)
							(mid 0.249642 0.249642)
							(end 0.2794 0.1778)
						)
						(arc
							(start 0.2794 -0.1778)
							(mid 0.249642 -0.249642)
							(end 0.1778 -0.2794)
						)
					)
					(width 0)
					(fill yes)
				)
			)
		)
	)
	(footprint ""
		(layer "F.Cu")
		(at 216.153746 -77.9907 180)
		(property "Reference" "C173"
			(at 0 0 180)
			(layer "F.SilkS")
			(hide yes)
			(effects
				(font
					(size 1.27 1.27)
				)
			)
		)
		(property "Value" "SC10U16V6KX-2GP"
			(at -0.0762 -5.1308 180)
			(unlocked yes)
			(layer "F.Fab")
			(hide yes)
			(effects
				(font
					(size 1.016 1.016)
					(thickness 0.1524)
				)
			)
		)
		(property "Device Type" "C1206H71"
			(at -0.127 -6.6548 180)
			(unlocked yes)
			(layer "F.Fab")
			(hide yes)
			(effects
				(font
					(size 1.016 1.016)
					(thickness 0.1524)
				)
			)
		)
		(duplicate_pad_numbers_are_jumpers no)
		(fp_line
			(start 1.016 2.2352)
			(end -1.016 2.2352)
			(stroke
				(width 0.1524)
				(type default)
			)
			(layer "F.SilkS")
		)
		(fp_line
			(start 1.016 0.8382)
			(end 1.016 2.2352)
			(stroke
				(width 0.1524)
				(type default)
			)
			(layer "F.SilkS")
		)
		(fp_line
			(start 1.016 -2.2352)
			(end 1.016 -0.8382)
			(stroke
				(width 0.1524)
				(type default)
			)
			(layer "F.SilkS")
		)
		(fp_line
			(start -1.016 2.2352)
			(end -1.016 0.8382)
			(stroke
				(width 0.1524)
				(type default)
			)
			(layer "F.SilkS")
		)
		(fp_line
			(start -1.016 -0.8382)
			(end -1.016 -2.2352)
			(stroke
				(width 0.1524)
				(type default)
			)
			(layer "F.SilkS")
		)
		(fp_line
			(start -1.016 -2.2352)
			(end 1.016 -2.2352)
			(stroke
				(width 0.1524)
				(type default)
			)
			(layer "F.SilkS")
		)
		(fp_rect
			(start -1.0922 2.3114)
			(end 1.0922 -2.3114)
			(stroke
				(width 0)
				(type default)
			)
			(fill no)
			(layer "F.CrtYd")
		)
		(fp_poly
			(pts
				(xy 1.0922 -2.3114) (xy 1.0922 2.3114) (xy -1.0922 2.3114) (xy -1.0922 -2.3114)
			)
			(stroke
				(width 0)
				(type default)
			)
			(fill no)
			(layer "F.Fab")
		)
		(pad "1" smd rect
			(at 0 -1.397 180)
			(size 1.651 1.27)
			(layers "F.Cu" "F.Mask" "F.Paste")
			(net "P5V_HDD4")
		)
		(pad "2" smd rect
			(at 0 1.397 180)
			(size 1.651 1.27)
			(layers "F.Cu" "F.Mask" "F.Paste")
			(net "GND")
		)
	)
	(footprint ""
		(layer "F.Cu")
		(at 80.6958 -196.1388 -90)
		(property "Reference" "R416"
			(at 0 0 270)
			(layer "F.SilkS")
			(hide yes)
			(effects
				(font
					(size 1.27 1.27)
				)
			)
		)
		(property "Value" "0R2J-2-GP"
			(at 0.064008 -3.993896 270)
			(unlocked yes)
			(layer "F.Fab")
			(hide yes)
			(effects
				(font
					(size 1.016 1.016)
					(thickness 0.1524)
				)
			)
		)
		(property "Device Type" "R402H16"
			(at 0.064008 -5.517896 270)
			(unlocked yes)
			(layer "F.Fab")
			(hide yes)
			(effects
				(font
					(size 1.016 1.016)
					(thickness 0.1524)
				)
			)
		)
		(duplicate_pad_numbers_are_jumpers no)
		(fp_line
			(start -0.508 -0.9398)
			(end -0.508 0.9398)
			(stroke
				(width 0.1524)
				(type default)
			)
			(layer "F.SilkS")
		)
		(fp_line
			(start 0.508 -0.9398)
			(end -0.508 -0.9398)
			(stroke
				(width 0.1524)
				(type default)
			)
			(layer "F.SilkS")
		)
		(fp_rect
			(start -0.508 0.9398)
			(end 0.508 -0.9398)
			(stroke
				(width 0)
				(type default)
			)
			(fill no)
			(layer "F.CrtYd")
		)
		(fp_rect
			(start -0.508 0.9398)
			(end 0.508 -0.9398)
			(stroke
				(width 0)
				(type default)
			)
			(fill no)
			(layer "F.Fab")
		)
		(pad "1" smd custom
			(at 0 -0.4445 270)
			(size 0.1397 0.1397)
			(layers "F.Cu" "F.Mask" "F.Paste")
			(net "SW_HDD8_G")
			(options
				(clearance outline)
				(anchor circle)
			)
			(primitives
				(gr_poly
					(pts
						(arc
							(start -0.1778 -0.2794)
							(mid -0.249642 -0.249642)
							(end -0.2794 -0.1778)
						)
						(arc
							(start -0.2794 0.1778)
							(mid -0.249642 0.249642)
							(end -0.1778 0.2794)
						)
						(arc
							(start 0.1778 0.2794)
							(mid 0.249642 0.249642)
							(end 0.2794 0.1778)
						)
						(arc
							(start 0.2794 -0.1778)
							(mid 0.249642 -0.249642)
							(end 0.1778 -0.2794)
						)
					)
					(width 0)
					(fill yes)
				)
			)
		)
		(pad "2" smd custom
			(at 0 0.4445 270)
			(size 0.1397 0.1397)
			(layers "F.Cu" "F.Mask" "F.Paste")
			(net "SW_HDD8_R")
			(options
				(clearance outline)
				(anchor circle)
			)
			(primitives
				(gr_poly
					(pts
						(arc
							(start -0.1778 -0.2794)
							(mid -0.249642 -0.249642)
							(end -0.2794 -0.1778)
						)
						(arc
							(start -0.2794 0.1778)
							(mid -0.249642 0.249642)
							(end -0.1778 0.2794)
						)
						(arc
							(start 0.1778 0.2794)
							(mid 0.249642 0.249642)
							(end 0.2794 0.1778)
						)
						(arc
							(start 0.2794 -0.1778)
							(mid 0.249642 -0.249642)
							(end 0.1778 -0.2794)
						)
					)
					(width 0)
					(fill yes)
				)
			)
		)
	)
	(footprint ""
		(layer "F.Cu")
		(at 207.136746 -463.6897 90)
		(property "Reference" "R326"
			(at 0 0 90)
			(layer "F.SilkS")
			(hide yes)
			(effects
				(font
					(size 1.27 1.27)
				)
			)
		)
		(property "Value" "0R2J-2-GP"
			(at 0.064008 -3.993896 90)
			(unlocked yes)
			(layer "F.Fab")
			(hide yes)
			(effects
				(font
					(size 1.016 1.016)
					(thickness 0.1524)
				)
			)
		)
		(property "Device Type" "R402H16"
			(at 0.064008 -5.517896 90)
			(unlocked yes)
			(layer "F.Fab")
			(hide yes)
			(effects
				(font
					(size 1.016 1.016)
					(thickness 0.1524)
				)
			)
		)
		(duplicate_pad_numbers_are_jumpers no)
		(fp_line
			(start 0.508 -0.9398)
			(end -0.508 -0.9398)
			(stroke
				(width 0.1524)
				(type default)
			)
			(layer "F.SilkS")
		)
		(fp_line
			(start -0.508 -0.9398)
			(end -0.508 0.9398)
			(stroke
				(width 0.1524)
				(type default)
			)
			(layer "F.SilkS")
		)
		(fp_rect
			(start -0.508 0.9398)
			(end 0.508 -0.9398)
			(stroke
				(width 0)
				(type default)
			)
			(fill no)
			(layer "F.CrtYd")
		)
		(fp_rect
			(start -0.508 0.9398)
			(end 0.508 -0.9398)
			(stroke
				(width 0)
				(type default)
			)
			(fill no)
			(layer "F.Fab")
		)
		(pad "1" smd custom
			(at 0 -0.4445 90)
			(size 0.1397 0.1397)
			(layers "F.Cu" "F.Mask" "F.Paste")
			(net "I2C_B_SDA")
			(options
				(clearance outline)
				(anchor circle)
			)
			(primitives
				(gr_poly
					(pts
						(arc
							(start -0.1778 -0.2794)
							(mid -0.249642 -0.249642)
							(end -0.2794 -0.1778)
						)
						(arc
							(start -0.2794 0.1778)
							(mid -0.249642 0.249642)
							(end -0.1778 0.2794)
						)
						(arc
							(start 0.1778 0.2794)
							(mid 0.249642 0.249642)
							(end 0.2794 0.1778)
						)
						(arc
							(start 0.2794 -0.1778)
							(mid 0.249642 -0.249642)
							(end 0.1778 -0.2794)
						)
					)
					(width 0)
					(fill yes)
				)
			)
		)
		(pad "2" smd custom
			(at 0 0.4445 90)
			(size 0.1397 0.1397)
			(layers "F.Cu" "F.Mask" "F.Paste")
			(net "TMP3_SDA")
			(options
				(clearance outline)
				(anchor circle)
			)
			(primitives
				(gr_poly
					(pts
						(arc
							(start -0.1778 -0.2794)
							(mid -0.249642 -0.249642)
							(end -0.2794 -0.1778)
						)
						(arc
							(start -0.2794 0.1778)
							(mid -0.249642 0.249642)
							(end -0.1778 0.2794)
						)
						(arc
							(start 0.1778 0.2794)
							(mid 0.249642 0.249642)
							(end 0.2794 0.1778)
						)
						(arc
							(start 0.2794 -0.1778)
							(mid 0.249642 -0.249642)
							(end 0.1778 -0.2794)
						)
					)
					(width 0)
					(fill yes)
				)
			)
		)
	)
	(footprint ""
		(layer "F.Cu")
		(at 37.210746 -112.296702 180)
		(property "Reference" "R295"
			(at 0 0 180)
			(layer "F.SilkS")
			(hide yes)
			(effects
				(font
					(size 1.27 1.27)
				)
			)
		)
		(property "Value" "0R2J-2-GP"
			(at 0.064008 -3.993896 180)
			(unlocked yes)
			(layer "F.Fab")
			(hide yes)
			(effects
				(font
					(size 1.016 1.016)
					(thickness 0.1524)
				)
			)
		)
		(property "Device Type" "R402H16"
			(at 0.064008 -5.517896 180)
			(unlocked yes)
			(layer "F.Fab")
			(hide yes)
			(effects
				(font
					(size 1.016 1.016)
					(thickness 0.1524)
				)
			)
		)
		(duplicate_pad_numbers_are_jumpers no)
		(fp_line
			(start 0.508 -0.9398)
			(end -0.508 -0.9398)
			(stroke
				(width 0.1524)
				(type default)
			)
			(layer "F.SilkS")
		)
		(fp_line
			(start -0.508 -0.9398)
			(end -0.508 0.9398)
			(stroke
				(width 0.1524)
				(type default)
			)
			(layer "F.SilkS")
		)
		(fp_rect
			(start -0.508 0.9398)
			(end 0.508 -0.9398)
			(stroke
				(width 0)
				(type default)
			)
			(fill no)
			(layer "F.CrtYd")
		)
		(fp_rect
			(start -0.508 0.9398)
			(end 0.508 -0.9398)
			(stroke
				(width 0)
				(type default)
			)
			(fill no)
			(layer "F.Fab")
		)
		(pad "1" smd custom
			(at 0 -0.4445 180)
			(size 0.1397 0.1397)
			(layers "F.Cu" "F.Mask" "F.Paste")
			(net "DRIVE_PWR13")
			(options
				(clearance outline)
				(anchor circle)
			)
			(primitives
				(gr_poly
					(pts
						(arc
							(start -0.1778 -0.2794)
							(mid -0.249642 -0.249642)
							(end -0.2794 -0.1778)
						)
						(arc
							(start -0.2794 0.1778)
							(mid -0.249642 0.249642)
							(end -0.1778 0.2794)
						)
						(arc
							(start 0.1778 0.2794)
							(mid 0.249642 0.249642)
							(end 0.2794 0.1778)
						)
						(arc
							(start 0.2794 -0.1778)
							(mid 0.249642 -0.249642)
							(end 0.1778 -0.2794)
						)
					)
					(width 0)
					(fill yes)
				)
			)
		)
		(pad "2" smd custom
			(at 0 0.4445 180)
			(size 0.1397 0.1397)
			(layers "F.Cu" "F.Mask" "F.Paste")
			(net "SW_PWR_HDD13")
			(options
				(clearance outline)
				(anchor circle)
			)
			(primitives
				(gr_poly
					(pts
						(arc
							(start -0.1778 -0.2794)
							(mid -0.249642 -0.249642)
							(end -0.2794 -0.1778)
						)
						(arc
							(start -0.2794 0.1778)
							(mid -0.249642 0.249642)
							(end -0.1778 0.2794)
						)
						(arc
							(start 0.1778 0.2794)
							(mid 0.249642 0.249642)
							(end 0.2794 0.1778)
						)
						(arc
							(start 0.2794 -0.1778)
							(mid 0.249642 -0.249642)
							(end 0.1778 -0.2794)
						)
					)
					(width 0)
					(fill yes)
				)
			)
		)
	)
	(footprint ""
		(layer "F.Cu")
		(at 78.358746 -188.4807 -90)
		(property "Reference" "R220"
			(at 0 0 270)
			(layer "F.SilkS")
			(hide yes)
			(effects
				(font
					(size 1.27 1.27)
				)
			)
		)
		(property "Value" "1KR2F-3-GP"
			(at 0.064008 -3.993896 270)
			(unlocked yes)
			(layer "F.Fab")
			(hide yes)
			(effects
				(font
					(size 1.016 1.016)
					(thickness 0.1524)
				)
			)
		)
		(property "Device Type" "R402H16"
			(at 0.064008 -5.517896 270)
			(unlocked yes)
			(layer "F.Fab")
			(hide yes)
			(effects
				(font
					(size 1.016 1.016)
					(thickness 0.1524)
				)
			)
		)
		(duplicate_pad_numbers_are_jumpers no)
		(fp_line
			(start -0.508 -0.9398)
			(end -0.508 0.9398)
			(stroke
				(width 0.1524)
				(type default)
			)
			(layer "F.SilkS")
		)
		(fp_line
			(start 0.508 -0.9398)
			(end -0.508 -0.9398)
			(stroke
				(width 0.1524)
				(type default)
			)
			(layer "F.SilkS")
		)
		(fp_rect
			(start -0.508 0.9398)
			(end 0.508 -0.9398)
			(stroke
				(width 0)
				(type default)
			)
			(fill no)
			(layer "F.CrtYd")
		)
		(fp_rect
			(start -0.508 0.9398)
			(end 0.508 -0.9398)
			(stroke
				(width 0)
				(type default)
			)
			(fill no)
			(layer "F.Fab")
		)
		(pad "1" smd custom
			(at 0 -0.4445 270)
			(size 0.1397 0.1397)
			(layers "F.Cu" "F.Mask" "F.Paste")
			(net "P3V3")
			(options
				(clearance outline)
				(anchor circle)
			)
			(primitives
				(gr_poly
					(pts
						(arc
							(start -0.1778 -0.2794)
							(mid -0.249642 -0.249642)
							(end -0.2794 -0.1778)
						)
						(arc
							(start -0.2794 0.1778)
							(mid -0.249642 0.249642)
							(end -0.1778 0.2794)
						)
						(arc
							(start 0.1778 0.2794)
							(mid 0.249642 0.249642)
							(end 0.2794 0.1778)
						)
						(arc
							(start 0.2794 -0.1778)
							(mid 0.249642 -0.249642)
							(end 0.1778 -0.2794)
						)
					)
					(width 0)
					(fill yes)
				)
			)
		)
		(pad "2" smd custom
			(at 0 0.4445 270)
			(size 0.1397 0.1397)
			(layers "F.Cu" "F.Mask" "F.Paste")
			(net "SW_PWR_HDD8")
			(options
				(clearance outline)
				(anchor circle)
			)
			(primitives
				(gr_poly
					(pts
						(arc
							(start -0.1778 -0.2794)
							(mid -0.249642 -0.249642)
							(end -0.2794 -0.1778)
						)
						(arc
							(start -0.2794 0.1778)
							(mid -0.249642 0.249642)
							(end -0.1778 0.2794)
						)
						(arc
							(start 0.1778 0.2794)
							(mid 0.249642 0.249642)
							(end 0.2794 0.1778)
						)
						(arc
							(start 0.2794 -0.1778)
							(mid 0.249642 -0.249642)
							(end 0.1778 -0.2794)
						)
					)
					(width 0)
					(fill yes)
				)
			)
		)
	)
	(footprint ""
		(layer "F.Cu")
		(at 20.192746 -51.9557 -90)
		(property "Reference" "R297"
			(at 0 0 270)
			(layer "F.SilkS")
			(hide yes)
			(effects
				(font
					(size 1.27 1.27)
				)
			)
		)
		(property "Value" "402R2F-GP"
			(at 0.064008 -3.993896 270)
			(unlocked yes)
			(layer "F.Fab")
			(hide yes)
			(effects
				(font
					(size 1.016 1.016)
					(thickness 0.1524)
				)
			)
		)
		(property "Device Type" "R402H16"
			(at 0.064008 -5.517896 270)
			(unlocked yes)
			(layer "F.Fab")
			(hide yes)
			(effects
				(font
					(size 1.016 1.016)
					(thickness 0.1524)
				)
			)
		)
		(duplicate_pad_numbers_are_jumpers no)
		(fp_line
			(start -0.508 -0.9398)
			(end -0.508 0.9398)
			(stroke
				(width 0.1524)
				(type default)
			)
			(layer "F.SilkS")
		)
		(fp_line
			(start 0.508 -0.9398)
			(end -0.508 -0.9398)
			(stroke
				(width 0.1524)
				(type default)
			)
			(layer "F.SilkS")
		)
		(fp_rect
			(start -0.508 0.9398)
			(end 0.508 -0.9398)
			(stroke
				(width 0)
				(type default)
			)
			(fill no)
			(layer "F.CrtYd")
		)
		(fp_rect
			(start -0.508 0.9398)
			(end 0.508 -0.9398)
			(stroke
				(width 0)
				(type default)
			)
			(fill no)
			(layer "F.Fab")
		)
		(pad "1" smd custom
			(at 0 -0.4445 270)
			(size 0.1397 0.1397)
			(layers "F.Cu" "F.Mask" "F.Paste")
			(net "P5VC_HDD14_LED")
			(options
				(clearance outline)
				(anchor circle)
			)
			(primitives
				(gr_poly
					(pts
						(arc
							(start -0.1778 -0.2794)
							(mid -0.249642 -0.249642)
							(end -0.2794 -0.1778)
						)
						(arc
							(start -0.2794 0.1778)
							(mid -0.249642 0.249642)
							(end -0.1778 0.2794)
						)
						(arc
							(start 0.1778 0.2794)
							(mid 0.249642 0.249642)
							(end 0.2794 0.1778)
						)
						(arc
							(start 0.2794 -0.1778)
							(mid 0.249642 -0.249642)
							(end 0.1778 -0.2794)
						)
					)
					(width 0)
					(fill yes)
				)
			)
		)
		(pad "2" smd custom
			(at 0 0.4445 270)
			(size 0.1397 0.1397)
			(layers "F.Cu" "F.Mask" "F.Paste")
			(net "DRV_ACT_14")
			(options
				(clearance outline)
				(anchor circle)
			)
			(primitives
				(gr_poly
					(pts
						(arc
							(start -0.1778 -0.2794)
							(mid -0.249642 -0.249642)
							(end -0.2794 -0.1778)
						)
						(arc
							(start -0.2794 0.1778)
							(mid -0.249642 0.249642)
							(end -0.1778 0.2794)
						)
						(arc
							(start 0.1778 0.2794)
							(mid 0.249642 0.249642)
							(end 0.2794 0.1778)
						)
						(arc
							(start 0.2794 -0.1778)
							(mid 0.249642 -0.249642)
							(end 0.1778 -0.2794)
						)
					)
					(width 0)
					(fill yes)
				)
			)
		)
	)
)
